(kicad_pcb
	(version 20260206)
	(generator "pcbnew")
	(generator_version "10.0")
	(general
		(thickness 1.6)
		(legacy_teardrops no)
	)
	(paper "A4")
	(title_block
		(title "01162023_DA0F0TEBIF0_F0T_Expander_BD_F_brd_V02_OCP.brd")
		(comment 1 "Grand Teton / footprints 2194-2200 of 9728")
	)
	(layers
		(0 "F.Cu" signal "TOP")
		(4 "In1.Cu" signal "GND")
		(6 "In2.Cu" signal "VCC")
		(8 "In3.Cu" signal "VCC1")
		(10 "In4.Cu" signal "GND1")
		(12 "In5.Cu" signal "IN1")
		(14 "In6.Cu" signal "GND2")
		(16 "In7.Cu" signal "IN2")
		(18 "In8.Cu" signal "GND3")
		(20 "In9.Cu" signal "IN3")
		(22 "In10.Cu" signal "GND4")
		(24 "In11.Cu" signal "IN4")
		(26 "In12.Cu" signal "GND5")
		(28 "In13.Cu" signal "IN5")
		(30 "In14.Cu" signal "GND6")
		(32 "In15.Cu" signal "IN6")
		(34 "In16.Cu" signal "GND7")
		(2 "B.Cu" signal "BOTTOM")
		(9 "F.Adhes" user "F.Adhesive")
		(11 "B.Adhes" user "B.Adhesive")
		(13 "F.Paste" user "Package Geometry/Pastemask Top")
		(15 "B.Paste" user "Package Geometry/Pastemask Bottom")
		(5 "F.SilkS" user "Ref Des/Silkscreen Top")
		(7 "B.SilkS" user "Ref Des/Silkscreen Bottom")
		(1 "F.Mask" user "Board Geometry/Soldermask Top")
		(3 "B.Mask" user "Board Geometry/Soldermask Bottom")
		(17 "Dwgs.User" user "User.Drawings")
		(19 "Cmts.User" user "User.Comments")
		(21 "Eco1.User" user "User.Eco1")
		(23 "Eco2.User" user "User.Eco2")
		(25 "Edge.Cuts" user "Board Geometry/Outline")
		(27 "Margin" user)
		(31 "F.CrtYd" user "Package Geometry/Place Bound Top")
		(29 "B.CrtYd" user "Package Geometry/Place Bound Bottom")
		(35 "F.Fab" user "Ref Des/Assembly Top")
		(33 "B.Fab" user "Ref Des/Assembly Bottom")
	)
	(footprint ""
		(layer "F.Cu")
		(at 127.658114 -255.210564 180)
		(property "Reference" "C200"
			(at 0 0 180)
			(layer "F.SilkS")
			(hide yes)
			(effects
				(font
					(size 1.27 1.27)
				)
			)
		)
		(property "Value" ""
			(at 0 0 180)
			(layer "F.Fab")
			(effects
				(font
					(size 1.27 1.27)
				)
			)
		)
		(duplicate_pad_numbers_are_jumpers no)
		(fp_line
			(start 0.7874 0.4064)
			(end -0.7874 0.4064)
			(stroke
				(width 0.1524)
				(type default)
			)
			(layer "F.SilkS")
		)
		(fp_line
			(start 0.7874 -0.4064)
			(end 0.7874 0.4064)
			(stroke
				(width 0.1524)
				(type default)
			)
			(layer "F.SilkS")
		)
		(fp_line
			(start -0.7874 0.4064)
			(end -0.7874 -0.4064)
			(stroke
				(width 0.1524)
				(type default)
			)
			(layer "F.SilkS")
		)
		(fp_line
			(start -0.7874 -0.4064)
			(end 0.7874 -0.4064)
			(stroke
				(width 0.1524)
				(type default)
			)
			(layer "F.SilkS")
		)
		(fp_line
			(start 0.67945 0.3048)
			(end 0.120396 0.3048)
			(stroke
				(width 0.1)
				(type default)
			)
			(layer "F.Fab")
		)
		(fp_line
			(start 0.67945 -0.3048)
			(end 0.67945 0.3048)
			(stroke
				(width 0.1)
				(type default)
			)
			(layer "F.Fab")
		)
		(fp_line
			(start 0.12065 -0.2794)
			(end 0.12065 -0.3048)
			(stroke
				(width 0.1)
				(type default)
			)
			(layer "F.Fab")
		)
		(fp_line
			(start 0.12065 -0.3048)
			(end 0.67945 -0.3048)
			(stroke
				(width 0.1)
				(type default)
			)
			(layer "F.Fab")
		)
		(fp_line
			(start 0.120396 0.3048)
			(end 0.120396 0.2794)
			(stroke
				(width 0.1)
				(type default)
			)
			(layer "F.Fab")
		)
		(fp_line
			(start 0.120396 0.2794)
			(end -0.12065 0.2794)
			(stroke
				(width 0.1)
				(type default)
			)
			(layer "F.Fab")
		)
		(fp_line
			(start -0.12065 0.3048)
			(end -0.67945 0.3048)
			(stroke
				(width 0.1)
				(type default)
			)
			(layer "F.Fab")
		)
		(fp_line
			(start -0.12065 0.2794)
			(end -0.12065 0.3048)
			(stroke
				(width 0.1)
				(type default)
			)
			(layer "F.Fab")
		)
		(fp_line
			(start -0.12065 -0.2794)
			(end 0.12065 -0.2794)
			(stroke
				(width 0.1)
				(type default)
			)
			(layer "F.Fab")
		)
		(fp_line
			(start -0.12065 -0.305054)
			(end -0.12065 -0.2794)
			(stroke
				(width 0.1)
				(type default)
			)
			(layer "F.Fab")
		)
		(fp_line
			(start -0.67945 0.3048)
			(end -0.67945 -0.305054)
			(stroke
				(width 0.1)
				(type default)
			)
			(layer "F.Fab")
		)
		(fp_line
			(start -0.67945 -0.305054)
			(end -0.12065 -0.305054)
			(stroke
				(width 0.1)
				(type default)
			)
			(layer "F.Fab")
		)
		(pad "1" smd circle
			(at -0.40005 0 180)
			(size 0 0)
			(layers "F.Cu" "F.Mask" "F.Paste")
			(net "GND")
		)
		(pad "2" smd circle
			(at 0.40005 0 180)
			(size 0 0)
			(layers "F.Cu" "F.Mask" "F.Paste")
			(net "FM_P0V8_PEX0_EN_R")
		)
	)
	(footprint ""
		(layer "F.Cu")
		(at 243.3066 -216.408 -90)
		(property "Reference" "R6589"
			(at 0 0 270)
			(layer "F.SilkS")
			(hide yes)
			(effects
				(font
					(size 1.27 1.27)
				)
			)
		)
		(property "Value" ""
			(at 0 0 270)
			(layer "F.Fab")
			(effects
				(font
					(size 1.27 1.27)
				)
			)
		)
		(duplicate_pad_numbers_are_jumpers no)
		(fp_line
			(start -0.7874 0.4064)
			(end -0.7874 -0.4064)
			(stroke
				(width 0.1524)
				(type default)
			)
			(layer "F.SilkS")
		)
		(fp_line
			(start 0.7874 0.4064)
			(end -0.7874 0.4064)
			(stroke
				(width 0.1524)
				(type default)
			)
			(layer "F.SilkS")
		)
		(fp_line
			(start -0.7874 -0.4064)
			(end 0.7874 -0.4064)
			(stroke
				(width 0.1524)
				(type default)
			)
			(layer "F.SilkS")
		)
		(fp_line
			(start 0.7874 -0.4064)
			(end 0.7874 0.4064)
			(stroke
				(width 0.1524)
				(type default)
			)
			(layer "F.SilkS")
		)
		(fp_line
			(start -0.67945 0.3048)
			(end -0.67945 -0.305054)
			(stroke
				(width 0.1)
				(type default)
			)
			(layer "F.Fab")
		)
		(fp_line
			(start -0.12065 0.3048)
			(end -0.67945 0.3048)
			(stroke
				(width 0.1)
				(type default)
			)
			(layer "F.Fab")
		)
		(fp_line
			(start 0.120396 0.3048)
			(end 0.120396 0.2794)
			(stroke
				(width 0.1)
				(type default)
			)
			(layer "F.Fab")
		)
		(fp_line
			(start 0.67945 0.3048)
			(end 0.120396 0.3048)
			(stroke
				(width 0.1)
				(type default)
			)
			(layer "F.Fab")
		)
		(fp_line
			(start -0.12065 0.2794)
			(end -0.12065 0.3048)
			(stroke
				(width 0.1)
				(type default)
			)
			(layer "F.Fab")
		)
		(fp_line
			(start 0.120396 0.2794)
			(end -0.12065 0.2794)
			(stroke
				(width 0.1)
				(type default)
			)
			(layer "F.Fab")
		)
		(fp_line
			(start -0.12065 -0.2794)
			(end 0.12065 -0.2794)
			(stroke
				(width 0.1)
				(type default)
			)
			(layer "F.Fab")
		)
		(fp_line
			(start 0.12065 -0.2794)
			(end 0.12065 -0.3048)
			(stroke
				(width 0.1)
				(type default)
			)
			(layer "F.Fab")
		)
		(fp_line
			(start 0.12065 -0.3048)
			(end 0.67945 -0.3048)
			(stroke
				(width 0.1)
				(type default)
			)
			(layer "F.Fab")
		)
		(fp_line
			(start 0.67945 -0.3048)
			(end 0.67945 0.3048)
			(stroke
				(width 0.1)
				(type default)
			)
			(layer "F.Fab")
		)
		(fp_line
			(start -0.67945 -0.305054)
			(end -0.12065 -0.305054)
			(stroke
				(width 0.1)
				(type default)
			)
			(layer "F.Fab")
		)
		(fp_line
			(start -0.12065 -0.305054)
			(end -0.12065 -0.2794)
			(stroke
				(width 0.1)
				(type default)
			)
			(layer "F.Fab")
		)
		(pad "1" smd circle
			(at -0.40005 0 270)
			(size 0 0)
			(layers "F.Cu" "F.Mask" "F.Paste")
			(net "P1V8_PLL0_PEX0")
		)
		(pad "2" smd circle
			(at 0.40005 0 270)
			(size 0 0)
			(layers "F.Cu" "F.Mask" "F.Paste")
			(net "P1V8_PLL0_PEX0_SCALED")
		)
	)
	(footprint ""
		(layer "F.Cu")
		(at 404.12924 -117.5512)
		(property "Reference" "R311"
			(at 0 0 0)
			(layer "F.SilkS")
			(hide yes)
			(effects
				(font
					(size 1.27 1.27)
				)
			)
		)
		(property "Value" ""
			(at 0 0 0)
			(layer "F.Fab")
			(effects
				(font
					(size 1.27 1.27)
				)
			)
		)
		(duplicate_pad_numbers_are_jumpers no)
		(fp_line
			(start -0.7874 -0.4064)
			(end 0.7874 -0.4064)
			(stroke
				(width 0.1524)
				(type default)
			)
			(layer "F.SilkS")
		)
		(fp_line
			(start -0.7874 0.4064)
			(end -0.7874 -0.4064)
			(stroke
				(width 0.1524)
				(type default)
			)
			(layer "F.SilkS")
		)
		(fp_line
			(start 0.7874 -0.4064)
			(end 0.7874 0.4064)
			(stroke
				(width 0.1524)
				(type default)
			)
			(layer "F.SilkS")
		)
		(fp_line
			(start 0.7874 0.4064)
			(end -0.7874 0.4064)
			(stroke
				(width 0.1524)
				(type default)
			)
			(layer "F.SilkS")
		)
		(fp_line
			(start -0.67945 -0.305054)
			(end -0.12065 -0.305054)
			(stroke
				(width 0.1)
				(type default)
			)
			(layer "F.Fab")
		)
		(fp_line
			(start -0.67945 0.3048)
			(end -0.67945 -0.305054)
			(stroke
				(width 0.1)
				(type default)
			)
			(layer "F.Fab")
		)
		(fp_line
			(start -0.12065 -0.305054)
			(end -0.12065 -0.2794)
			(stroke
				(width 0.1)
				(type default)
			)
			(layer "F.Fab")
		)
		(fp_line
			(start -0.12065 -0.2794)
			(end 0.12065 -0.2794)
			(stroke
				(width 0.1)
				(type default)
			)
			(layer "F.Fab")
		)
		(fp_line
			(start -0.12065 0.2794)
			(end -0.12065 0.3048)
			(stroke
				(width 0.1)
				(type default)
			)
			(layer "F.Fab")
		)
		(fp_line
			(start -0.12065 0.3048)
			(end -0.67945 0.3048)
			(stroke
				(width 0.1)
				(type default)
			)
			(layer "F.Fab")
		)
		(fp_line
			(start 0.120396 0.2794)
			(end -0.12065 0.2794)
			(stroke
				(width 0.1)
				(type default)
			)
			(layer "F.Fab")
		)
		(fp_line
			(start 0.120396 0.3048)
			(end 0.120396 0.2794)
			(stroke
				(width 0.1)
				(type default)
			)
			(layer "F.Fab")
		)
		(fp_line
			(start 0.12065 -0.3048)
			(end 0.67945 -0.3048)
			(stroke
				(width 0.1)
				(type default)
			)
			(layer "F.Fab")
		)
		(fp_line
			(start 0.12065 -0.2794)
			(end 0.12065 -0.3048)
			(stroke
				(width 0.1)
				(type default)
			)
			(layer "F.Fab")
		)
		(fp_line
			(start 0.67945 -0.3048)
			(end 0.67945 0.3048)
			(stroke
				(width 0.1)
				(type default)
			)
			(layer "F.Fab")
		)
		(fp_line
			(start 0.67945 0.3048)
			(end 0.120396 0.3048)
			(stroke
				(width 0.1)
				(type default)
			)
			(layer "F.Fab")
		)
		(pad "1" smd circle
			(at -0.40005 0)
			(size 0 0)
			(layers "F.Cu" "F.Mask" "F.Paste")
			(net "PRSNTB1_NIC6_N")
		)
		(pad "2" smd circle
			(at 0.40005 0)
			(size 0 0)
			(layers "F.Cu" "F.Mask" "F.Paste")
			(net "P3V3_AUX")
		)
	)
	(footprint ""
		(layer "F.Cu")
		(at 323.368924 -123.067318 90)
		(property "Reference" "PC467"
			(at 0 0 90)
			(layer "F.SilkS")
			(hide yes)
			(effects
				(font
					(size 1.27 1.27)
				)
			)
		)
		(property "Value" ""
			(at 0 0 90)
			(layer "F.Fab")
			(effects
				(font
					(size 1.27 1.27)
				)
			)
		)
		(duplicate_pad_numbers_are_jumpers no)
		(fp_line
			(start 1.524 -0.762)
			(end 1.524 0.762)
			(stroke
				(width 0.1524)
				(type default)
			)
			(layer "F.SilkS")
		)
		(fp_line
			(start -1.524 -0.762)
			(end 1.524 -0.762)
			(stroke
				(width 0.1524)
				(type default)
			)
			(layer "F.SilkS")
		)
		(fp_line
			(start 1.524 0.762)
			(end -1.524 0.762)
			(stroke
				(width 0.1524)
				(type default)
			)
			(layer "F.SilkS")
		)
		(fp_line
			(start -1.524 0.762)
			(end -1.524 -0.762)
			(stroke
				(width 0.1524)
				(type default)
			)
			(layer "F.SilkS")
		)
		(fp_line
			(start 1.1049 -0.724916)
			(end -1.1049 -0.724916)
			(stroke
				(width 0.1)
				(type default)
			)
			(layer "F.Fab")
		)
		(fp_line
			(start -1.1049 -0.724916)
			(end -1.1049 0.724916)
			(stroke
				(width 0.1)
				(type default)
			)
			(layer "F.Fab")
		)
		(fp_line
			(start 1.1049 0.724916)
			(end 1.1049 -0.724916)
			(stroke
				(width 0.1)
				(type default)
			)
			(layer "F.Fab")
		)
		(fp_line
			(start -1.1049 0.724916)
			(end 1.1049 0.724916)
			(stroke
				(width 0.1)
				(type default)
			)
			(layer "F.Fab")
		)
		(pad "1" smd rect
			(at -0.889 0 270)
			(size 1.016 1.27)
			(layers "F.Cu" "F.Mask" "F.Paste")
			(net "P3V3_NIC5")
		)
		(pad "2" smd rect
			(at 0.889 0 270)
			(size 1.016 1.27)
			(layers "F.Cu" "F.Mask" "F.Paste")
			(net "GND")
		)
	)
	(footprint ""
		(layer "F.Cu")
		(at 245.625112 -254.00889 -90)
		(property "Reference" "C4342"
			(at 0 0 270)
			(layer "F.SilkS")
			(hide yes)
			(effects
				(font
					(size 1.27 1.27)
				)
			)
		)
		(property "Value" ""
			(at 0 0 270)
			(layer "F.Fab")
			(effects
				(font
					(size 1.27 1.27)
				)
			)
		)
		(duplicate_pad_numbers_are_jumpers no)
		(fp_line
			(start -1.524 0.762)
			(end -1.524 -0.762)
			(stroke
				(width 0.1524)
				(type default)
			)
			(layer "F.SilkS")
		)
		(fp_line
			(start 1.524 0.762)
			(end -1.524 0.762)
			(stroke
				(width 0.1524)
				(type default)
			)
			(layer "F.SilkS")
		)
		(fp_line
			(start -1.524 -0.762)
			(end 1.524 -0.762)
			(stroke
				(width 0.1524)
				(type default)
			)
			(layer "F.SilkS")
		)
		(fp_line
			(start 1.524 -0.762)
			(end 1.524 0.762)
			(stroke
				(width 0.1524)
				(type default)
			)
			(layer "F.SilkS")
		)
		(fp_line
			(start -1.1049 0.724916)
			(end 1.1049 0.724916)
			(stroke
				(width 0.1)
				(type default)
			)
			(layer "F.Fab")
		)
		(fp_line
			(start 1.1049 0.724916)
			(end 1.1049 -0.724916)
			(stroke
				(width 0.1)
				(type default)
			)
			(layer "F.Fab")
		)
		(fp_line
			(start -1.1049 -0.724916)
			(end -1.1049 0.724916)
			(stroke
				(width 0.1)
				(type default)
			)
			(layer "F.Fab")
		)
		(fp_line
			(start 1.1049 -0.724916)
			(end -1.1049 -0.724916)
			(stroke
				(width 0.1)
				(type default)
			)
			(layer "F.Fab")
		)
		(pad "1" smd rect
			(at -0.889 0 90)
			(size 1.016 1.27)
			(layers "F.Cu" "F.Mask" "F.Paste")
			(net "P1V25_SERDES_VDDPLL_PEX2_C4")
		)
		(pad "2" smd rect
			(at 0.889 0 90)
			(size 1.016 1.27)
			(layers "F.Cu" "F.Mask" "F.Paste")
			(net "GND")
		)
		(zone
			(layer "F.Cu")
			(hatch none 0.5)
			(connect_pads
				(clearance 0)
			)
			(min_thickness 0.25)
			(keepout
				(tracks not_allowed)
				(vias allowed)
				(pads allowed)
				(copperpour not_allowed)
				(footprints allowed)
			)
			(placement
				(enabled no)
				(sheetname "")
			)
			(fill
				(thermal_gap 0.5)
				(thermal_bridge_width 0.5)
				(island_removal_mode 0)
			)
			(polygon
				(pts
					(xy 246.350028 -254.33909) (xy 244.900196 -254.33909) (xy 244.900196 -253.67869) (xy 246.350028 -253.67869)
				)
			)
		)
	)
	(footprint ""
		(layer "F.Cu")
		(at 162.225482 -42.849038 180)
		(property "Reference" "R568"
			(at 0 0 180)
			(layer "F.SilkS")
			(hide yes)
			(effects
				(font
					(size 1.27 1.27)
				)
			)
		)
		(property "Value" ""
			(at 0 0 180)
			(layer "F.Fab")
			(effects
				(font
					(size 1.27 1.27)
				)
			)
		)
		(duplicate_pad_numbers_are_jumpers no)
		(fp_line
			(start 0.7874 0.4064)
			(end -0.7874 0.4064)
			(stroke
				(width 0.1524)
				(type default)
			)
			(layer "F.SilkS")
		)
		(fp_line
			(start 0.7874 -0.4064)
			(end 0.7874 0.4064)
			(stroke
				(width 0.1524)
				(type default)
			)
			(layer "F.SilkS")
		)
		(fp_line
			(start -0.7874 0.4064)
			(end -0.7874 -0.4064)
			(stroke
				(width 0.1524)
				(type default)
			)
			(layer "F.SilkS")
		)
		(fp_line
			(start -0.7874 -0.4064)
			(end 0.7874 -0.4064)
			(stroke
				(width 0.1524)
				(type default)
			)
			(layer "F.SilkS")
		)
		(fp_line
			(start 0.67945 0.3048)
			(end 0.120396 0.3048)
			(stroke
				(width 0.1)
				(type default)
			)
			(layer "F.Fab")
		)
		(fp_line
			(start 0.67945 -0.3048)
			(end 0.67945 0.3048)
			(stroke
				(width 0.1)
				(type default)
			)
			(layer "F.Fab")
		)
		(fp_line
			(start 0.12065 -0.2794)
			(end 0.12065 -0.3048)
			(stroke
				(width 0.1)
				(type default)
			)
			(layer "F.Fab")
		)
		(fp_line
			(start 0.12065 -0.3048)
			(end 0.67945 -0.3048)
			(stroke
				(width 0.1)
				(type default)
			)
			(layer "F.Fab")
		)
		(fp_line
			(start 0.120396 0.3048)
			(end 0.120396 0.2794)
			(stroke
				(width 0.1)
				(type default)
			)
			(layer "F.Fab")
		)
		(fp_line
			(start 0.120396 0.2794)
			(end -0.12065 0.2794)
			(stroke
				(width 0.1)
				(type default)
			)
			(layer "F.Fab")
		)
		(fp_line
			(start -0.12065 0.3048)
			(end -0.67945 0.3048)
			(stroke
				(width 0.1)
				(type default)
			)
			(layer "F.Fab")
		)
		(fp_line
			(start -0.12065 0.2794)
			(end -0.12065 0.3048)
			(stroke
				(width 0.1)
				(type default)
			)
			(layer "F.Fab")
		)
		(fp_line
			(start -0.12065 -0.2794)
			(end 0.12065 -0.2794)
			(stroke
				(width 0.1)
				(type default)
			)
			(layer "F.Fab")
		)
		(fp_line
			(start -0.12065 -0.305054)
			(end -0.12065 -0.2794)
			(stroke
				(width 0.1)
				(type default)
			)
			(layer "F.Fab")
		)
		(fp_line
			(start -0.67945 0.3048)
			(end -0.67945 -0.305054)
			(stroke
				(width 0.1)
				(type default)
			)
			(layer "F.Fab")
		)
		(fp_line
			(start -0.67945 -0.305054)
			(end -0.12065 -0.305054)
			(stroke
				(width 0.1)
				(type default)
			)
			(layer "F.Fab")
		)
		(pad "1" smd circle
			(at -0.40005 0 180)
			(size 0 0)
			(layers "F.Cu" "F.Mask" "F.Paste")
			(net "P12V_SSD5_R")
		)
		(pad "2" smd circle
			(at 0.40005 0 180)
			(size 0 0)
			(layers "F.Cu" "F.Mask" "F.Paste")
			(net "P12V_SSD5_VIN_P")
		)
	)
	(footprint ""
		(layer "F.Cu")
		(at 447.802 -402.209 -90)
		(property "Reference" "R5588"
			(at 0 0 270)
			(layer "F.SilkS")
			(hide yes)
			(effects
				(font
					(size 1.27 1.27)
				)
			)
		)
		(property "Value" ""
			(at 0 0 270)
			(layer "F.Fab")
			(effects
				(font
					(size 1.27 1.27)
				)
			)
		)
		(duplicate_pad_numbers_are_jumpers no)
		(fp_line
			(start -0.7874 0.4064)
			(end -0.7874 -0.4064)
			(stroke
				(width 0.1524)
				(type default)
			)
			(layer "F.SilkS")
		)
		(fp_line
			(start 0.7874 0.4064)
			(end -0.7874 0.4064)
			(stroke
				(width 0.1524)
				(type default)
			)
			(layer "F.SilkS")
		)
		(fp_line
			(start -0.7874 -0.4064)
			(end 0.7874 -0.4064)
			(stroke
				(width 0.1524)
				(type default)
			)
			(layer "F.SilkS")
		)
		(fp_line
			(start 0.7874 -0.4064)
			(end 0.7874 0.4064)
			(stroke
				(width 0.1524)
				(type default)
			)
			(layer "F.SilkS")
		)
		(fp_line
			(start -0.67945 0.3048)
			(end -0.67945 -0.305054)
			(stroke
				(width 0.1)
				(type default)
			)
			(layer "F.Fab")
		)
		(fp_line
			(start -0.12065 0.3048)
			(end -0.67945 0.3048)
			(stroke
				(width 0.1)
				(type default)
			)
			(layer "F.Fab")
		)
		(fp_line
			(start 0.120396 0.3048)
			(end 0.120396 0.2794)
			(stroke
				(width 0.1)
				(type default)
			)
			(layer "F.Fab")
		)
		(fp_line
			(start 0.67945 0.3048)
			(end 0.120396 0.3048)
			(stroke
				(width 0.1)
				(type default)
			)
			(layer "F.Fab")
		)
		(fp_line
			(start -0.12065 0.2794)
			(end -0.12065 0.3048)
			(stroke
				(width 0.1)
				(type default)
			)
			(layer "F.Fab")
		)
		(fp_line
			(start 0.120396 0.2794)
			(end -0.12065 0.2794)
			(stroke
				(width 0.1)
				(type default)
			)
			(layer "F.Fab")
		)
		(fp_line
			(start -0.12065 -0.2794)
			(end 0.12065 -0.2794)
			(stroke
				(width 0.1)
				(type default)
			)
			(layer "F.Fab")
		)
		(fp_line
			(start 0.12065 -0.2794)
			(end 0.12065 -0.3048)
			(stroke
				(width 0.1)
				(type default)
			)
			(layer "F.Fab")
		)
		(fp_line
			(start 0.12065 -0.3048)
			(end 0.67945 -0.3048)
			(stroke
				(width 0.1)
				(type default)
			)
			(layer "F.Fab")
		)
		(fp_line
			(start 0.67945 -0.3048)
			(end 0.67945 0.3048)
			(stroke
				(width 0.1)
				(type default)
			)
			(layer "F.Fab")
		)
		(fp_line
			(start -0.67945 -0.305054)
			(end -0.12065 -0.305054)
			(stroke
				(width 0.1)
				(type default)
			)
			(layer "F.Fab")
		)
		(fp_line
			(start -0.12065 -0.305054)
			(end -0.12065 -0.2794)
			(stroke
				(width 0.1)
				(type default)
			)
			(layer "F.Fab")
		)
		(pad "1" smd circle
			(at -0.40005 0 270)
			(size 0 0)
			(layers "F.Cu" "F.Mask" "F.Paste")
			(net "SMB_BIC_I2C6_MUX_THERMAL_R1_SCL")
		)
		(pad "2" smd circle
			(at 0.40005 0 270)
			(size 0 0)
			(layers "F.Cu" "F.Mask" "F.Paste")
			(net "SMB_LM75_0_SCL")
		)
	)
)
